(kicad_pcb
	(version 20260206)
	(generator "pcbnew")
	(generator_version "10.0")
	(general
		(thickness 1.6)
		(legacy_teardrops no)
	)
	(paper "A4")
	(title_block
		(title "01162023_DA0F0TEBIF0_F0T_Expander_BD_F_brd_V02_OCP.brd")
		(comment 1 "Grand Teton / footprints 4484-4490 of 9728")
	)
	(layers
		(0 "F.Cu" signal "TOP")
		(4 "In1.Cu" signal "GND")
		(6 "In2.Cu" signal "VCC")
		(8 "In3.Cu" signal "VCC1")
		(10 "In4.Cu" signal "GND1")
		(12 "In5.Cu" signal "IN1")
		(14 "In6.Cu" signal "GND2")
		(16 "In7.Cu" signal "IN2")
		(18 "In8.Cu" signal "GND3")
		(20 "In9.Cu" signal "IN3")
		(22 "In10.Cu" signal "GND4")
		(24 "In11.Cu" signal "IN4")
		(26 "In12.Cu" signal "GND5")
		(28 "In13.Cu" signal "IN5")
		(30 "In14.Cu" signal "GND6")
		(32 "In15.Cu" signal "IN6")
		(34 "In16.Cu" signal "GND7")
		(2 "B.Cu" signal "BOTTOM")
		(9 "F.Adhes" user "F.Adhesive")
		(11 "B.Adhes" user "B.Adhesive")
		(13 "F.Paste" user "Package Geometry/Pastemask Top")
		(15 "B.Paste" user "Package Geometry/Pastemask Bottom")
		(5 "F.SilkS" user "Ref Des/Silkscreen Top")
		(7 "B.SilkS" user "Ref Des/Silkscreen Bottom")
		(1 "F.Mask" user "Board Geometry/Soldermask Top")
		(3 "B.Mask" user "Board Geometry/Soldermask Bottom")
		(17 "Dwgs.User" user "User.Drawings")
		(19 "Cmts.User" user "User.Comments")
		(21 "Eco1.User" user "User.Eco1")
		(23 "Eco2.User" user "User.Eco2")
		(25 "Edge.Cuts" user "Board Geometry/Outline")
		(27 "Margin" user)
		(31 "F.CrtYd" user "Package Geometry/Place Bound Top")
		(29 "B.CrtYd" user "Package Geometry/Place Bound Bottom")
		(35 "F.Fab" user "Ref Des/Assembly Top")
		(33 "B.Fab" user "Ref Des/Assembly Bottom")
	)
	(footprint ""
		(layer "F.Cu")
		(at 242.347496 -223.91878 90)
		(property "Reference" "R6194"
			(at 0 0 90)
			(layer "F.SilkS")
			(hide yes)
			(effects
				(font
					(size 1.27 1.27)
				)
			)
		)
		(property "Value" ""
			(at 0 0 90)
			(layer "F.Fab")
			(effects
				(font
					(size 1.27 1.27)
				)
			)
		)
		(duplicate_pad_numbers_are_jumpers no)
		(fp_line
			(start 0.7874 -0.4064)
			(end 0.7874 0.4064)
			(stroke
				(width 0.1524)
				(type default)
			)
			(layer "F.SilkS")
		)
		(fp_line
			(start -0.7874 -0.4064)
			(end 0.7874 -0.4064)
			(stroke
				(width 0.1524)
				(type default)
			)
			(layer "F.SilkS")
		)
		(fp_line
			(start 0.7874 0.4064)
			(end -0.7874 0.4064)
			(stroke
				(width 0.1524)
				(type default)
			)
			(layer "F.SilkS")
		)
		(fp_line
			(start -0.7874 0.4064)
			(end -0.7874 -0.4064)
			(stroke
				(width 0.1524)
				(type default)
			)
			(layer "F.SilkS")
		)
		(fp_line
			(start -0.12065 -0.305054)
			(end -0.12065 -0.2794)
			(stroke
				(width 0.1)
				(type default)
			)
			(layer "F.Fab")
		)
		(fp_line
			(start -0.67945 -0.305054)
			(end -0.12065 -0.305054)
			(stroke
				(width 0.1)
				(type default)
			)
			(layer "F.Fab")
		)
		(fp_line
			(start 0.67945 -0.3048)
			(end 0.67945 0.3048)
			(stroke
				(width 0.1)
				(type default)
			)
			(layer "F.Fab")
		)
		(fp_line
			(start 0.12065 -0.3048)
			(end 0.67945 -0.3048)
			(stroke
				(width 0.1)
				(type default)
			)
			(layer "F.Fab")
		)
		(fp_line
			(start 0.12065 -0.2794)
			(end 0.12065 -0.3048)
			(stroke
				(width 0.1)
				(type default)
			)
			(layer "F.Fab")
		)
		(fp_line
			(start -0.12065 -0.2794)
			(end 0.12065 -0.2794)
			(stroke
				(width 0.1)
				(type default)
			)
			(layer "F.Fab")
		)
		(fp_line
			(start 0.120396 0.2794)
			(end -0.12065 0.2794)
			(stroke
				(width 0.1)
				(type default)
			)
			(layer "F.Fab")
		)
		(fp_line
			(start -0.12065 0.2794)
			(end -0.12065 0.3048)
			(stroke
				(width 0.1)
				(type default)
			)
			(layer "F.Fab")
		)
		(fp_line
			(start 0.67945 0.3048)
			(end 0.120396 0.3048)
			(stroke
				(width 0.1)
				(type default)
			)
			(layer "F.Fab")
		)
		(fp_line
			(start 0.120396 0.3048)
			(end 0.120396 0.2794)
			(stroke
				(width 0.1)
				(type default)
			)
			(layer "F.Fab")
		)
		(fp_line
			(start -0.12065 0.3048)
			(end -0.67945 0.3048)
			(stroke
				(width 0.1)
				(type default)
			)
			(layer "F.Fab")
		)
		(fp_line
			(start -0.67945 0.3048)
			(end -0.67945 -0.305054)
			(stroke
				(width 0.1)
				(type default)
			)
			(layer "F.Fab")
		)
		(pad "1" smd circle
			(at -0.40005 0 90)
			(size 0 0)
			(layers "F.Cu" "F.Mask" "F.Paste")
			(net "GND")
		)
		(pad "2" smd circle
			(at 0.40005 0 90)
			(size 0 0)
			(layers "F.Cu" "F.Mask" "F.Paste")
			(net "SSD12_PWRDIS_BIC_R")
		)
	)
	(footprint ""
		(layer "F.Cu")
		(at 281.221942 -356.244906 90)
		(property "Reference" "C2354"
			(at 0 0 90)
			(layer "F.SilkS")
			(hide yes)
			(effects
				(font
					(size 1.27 1.27)
				)
			)
		)
		(property "Value" ""
			(at 0 0 90)
			(layer "F.Fab")
			(effects
				(font
					(size 1.27 1.27)
				)
			)
		)
		(duplicate_pad_numbers_are_jumpers no)
		(fp_line
			(start 0.299974 -0.150114)
			(end 0.299974 0.150114)
			(stroke
				(width 0.1)
				(type default)
			)
			(layer "F.Fab")
		)
		(fp_line
			(start -0.299974 -0.150114)
			(end 0.299974 -0.150114)
			(stroke
				(width 0.1)
				(type default)
			)
			(layer "F.Fab")
		)
		(fp_line
			(start 0.299974 0.150114)
			(end -0.299974 0.150114)
			(stroke
				(width 0.1)
				(type default)
			)
			(layer "F.Fab")
		)
		(fp_line
			(start -0.299974 0.150114)
			(end -0.299974 -0.150114)
			(stroke
				(width 0.1)
				(type default)
			)
			(layer "F.Fab")
		)
		(pad "1" smd rect
			(at -0.2667 0 90)
			(size 0.3048 0.381)
			(layers "F.Cu" "F.Mask" "F.Paste")
			(net "P5E_PEX2_STN4_TX_DN<73>")
		)
		(pad "2" smd rect
			(at 0.2667 0 90)
			(size 0.3048 0.381)
			(layers "F.Cu" "F.Mask" "F.Paste")
			(net "P5E_PEX2_STN4_TX_C_DN<73>")
		)
	)
	(footprint ""
		(layer "F.Cu")
		(at 350.139 -234.061 -90)
		(property "Reference" "R3576"
			(at 0 0 270)
			(layer "F.SilkS")
			(hide yes)
			(effects
				(font
					(size 1.27 1.27)
				)
			)
		)
		(property "Value" ""
			(at 0 0 270)
			(layer "F.Fab")
			(effects
				(font
					(size 1.27 1.27)
				)
			)
		)
		(duplicate_pad_numbers_are_jumpers no)
		(fp_line
			(start -0.7874 0.4064)
			(end -0.7874 -0.4064)
			(stroke
				(width 0.1524)
				(type default)
			)
			(layer "F.SilkS")
		)
		(fp_line
			(start 0.7874 0.4064)
			(end -0.7874 0.4064)
			(stroke
				(width 0.1524)
				(type default)
			)
			(layer "F.SilkS")
		)
		(fp_line
			(start -0.7874 -0.4064)
			(end 0.7874 -0.4064)
			(stroke
				(width 0.1524)
				(type default)
			)
			(layer "F.SilkS")
		)
		(fp_line
			(start 0.7874 -0.4064)
			(end 0.7874 0.4064)
			(stroke
				(width 0.1524)
				(type default)
			)
			(layer "F.SilkS")
		)
		(fp_line
			(start -0.67945 0.3048)
			(end -0.67945 -0.305054)
			(stroke
				(width 0.1)
				(type default)
			)
			(layer "F.Fab")
		)
		(fp_line
			(start -0.12065 0.3048)
			(end -0.67945 0.3048)
			(stroke
				(width 0.1)
				(type default)
			)
			(layer "F.Fab")
		)
		(fp_line
			(start 0.120396 0.3048)
			(end 0.120396 0.2794)
			(stroke
				(width 0.1)
				(type default)
			)
			(layer "F.Fab")
		)
		(fp_line
			(start 0.67945 0.3048)
			(end 0.120396 0.3048)
			(stroke
				(width 0.1)
				(type default)
			)
			(layer "F.Fab")
		)
		(fp_line
			(start -0.12065 0.2794)
			(end -0.12065 0.3048)
			(stroke
				(width 0.1)
				(type default)
			)
			(layer "F.Fab")
		)
		(fp_line
			(start 0.120396 0.2794)
			(end -0.12065 0.2794)
			(stroke
				(width 0.1)
				(type default)
			)
			(layer "F.Fab")
		)
		(fp_line
			(start -0.12065 -0.2794)
			(end 0.12065 -0.2794)
			(stroke
				(width 0.1)
				(type default)
			)
			(layer "F.Fab")
		)
		(fp_line
			(start 0.12065 -0.2794)
			(end 0.12065 -0.3048)
			(stroke
				(width 0.1)
				(type default)
			)
			(layer "F.Fab")
		)
		(fp_line
			(start 0.12065 -0.3048)
			(end 0.67945 -0.3048)
			(stroke
				(width 0.1)
				(type default)
			)
			(layer "F.Fab")
		)
		(fp_line
			(start 0.67945 -0.3048)
			(end 0.67945 0.3048)
			(stroke
				(width 0.1)
				(type default)
			)
			(layer "F.Fab")
		)
		(fp_line
			(start -0.67945 -0.305054)
			(end -0.12065 -0.305054)
			(stroke
				(width 0.1)
				(type default)
			)
			(layer "F.Fab")
		)
		(fp_line
			(start -0.12065 -0.305054)
			(end -0.12065 -0.2794)
			(stroke
				(width 0.1)
				(type default)
			)
			(layer "F.Fab")
		)
		(pad "1" smd circle
			(at -0.40005 0 270)
			(size 0 0)
			(layers "F.Cu" "F.Mask" "F.Paste")
			(net "SSD6_PWR_EN_R")
		)
		(pad "2" smd circle
			(at 0.40005 0 270)
			(size 0 0)
			(layers "F.Cu" "F.Mask" "F.Paste")
			(net "SSD6_PWR_EN")
		)
	)
	(footprint ""
		(layer "F.Cu")
		(at 206.623158 -78.579472)
		(property "Reference" "R4308"
			(at 0 0 0)
			(layer "F.SilkS")
			(hide yes)
			(effects
				(font
					(size 1.27 1.27)
				)
			)
		)
		(property "Value" ""
			(at 0 0 0)
			(layer "F.Fab")
			(effects
				(font
					(size 1.27 1.27)
				)
			)
		)
		(duplicate_pad_numbers_are_jumpers no)
		(fp_line
			(start -0.7874 -0.4064)
			(end 0.7874 -0.4064)
			(stroke
				(width 0.1524)
				(type default)
			)
			(layer "F.SilkS")
		)
		(fp_line
			(start -0.7874 0.4064)
			(end -0.7874 -0.4064)
			(stroke
				(width 0.1524)
				(type default)
			)
			(layer "F.SilkS")
		)
		(fp_line
			(start 0.7874 -0.4064)
			(end 0.7874 0.4064)
			(stroke
				(width 0.1524)
				(type default)
			)
			(layer "F.SilkS")
		)
		(fp_line
			(start 0.7874 0.4064)
			(end -0.7874 0.4064)
			(stroke
				(width 0.1524)
				(type default)
			)
			(layer "F.SilkS")
		)
		(fp_line
			(start -0.67945 -0.305054)
			(end -0.12065 -0.305054)
			(stroke
				(width 0.1)
				(type default)
			)
			(layer "F.Fab")
		)
		(fp_line
			(start -0.67945 0.3048)
			(end -0.67945 -0.305054)
			(stroke
				(width 0.1)
				(type default)
			)
			(layer "F.Fab")
		)
		(fp_line
			(start -0.12065 -0.305054)
			(end -0.12065 -0.2794)
			(stroke
				(width 0.1)
				(type default)
			)
			(layer "F.Fab")
		)
		(fp_line
			(start -0.12065 -0.2794)
			(end 0.12065 -0.2794)
			(stroke
				(width 0.1)
				(type default)
			)
			(layer "F.Fab")
		)
		(fp_line
			(start -0.12065 0.2794)
			(end -0.12065 0.3048)
			(stroke
				(width 0.1)
				(type default)
			)
			(layer "F.Fab")
		)
		(fp_line
			(start -0.12065 0.3048)
			(end -0.67945 0.3048)
			(stroke
				(width 0.1)
				(type default)
			)
			(layer "F.Fab")
		)
		(fp_line
			(start 0.120396 0.2794)
			(end -0.12065 0.2794)
			(stroke
				(width 0.1)
				(type default)
			)
			(layer "F.Fab")
		)
		(fp_line
			(start 0.120396 0.3048)
			(end 0.120396 0.2794)
			(stroke
				(width 0.1)
				(type default)
			)
			(layer "F.Fab")
		)
		(fp_line
			(start 0.12065 -0.3048)
			(end 0.67945 -0.3048)
			(stroke
				(width 0.1)
				(type default)
			)
			(layer "F.Fab")
		)
		(fp_line
			(start 0.12065 -0.2794)
			(end 0.12065 -0.3048)
			(stroke
				(width 0.1)
				(type default)
			)
			(layer "F.Fab")
		)
		(fp_line
			(start 0.67945 -0.3048)
			(end 0.67945 0.3048)
			(stroke
				(width 0.1)
				(type default)
			)
			(layer "F.Fab")
		)
		(fp_line
			(start 0.67945 0.3048)
			(end 0.120396 0.3048)
			(stroke
				(width 0.1)
				(type default)
			)
			(layer "F.Fab")
		)
		(pad "1" smd circle
			(at -0.40005 0)
			(size 0 0)
			(layers "F.Cu" "F.Mask" "F.Paste")
			(net "SSD6_LED_R")
		)
		(pad "2" smd circle
			(at 0.40005 0)
			(size 0 0)
			(layers "F.Cu" "F.Mask" "F.Paste")
			(net "SSD6_LED")
		)
	)
	(footprint ""
		(layer "F.Cu")
		(at 168.343834 -47.92091)
		(property "Reference" "R559"
			(at 0 0 0)
			(layer "F.SilkS")
			(hide yes)
			(effects
				(font
					(size 1.27 1.27)
				)
			)
		)
		(property "Value" ""
			(at 0 0 0)
			(layer "F.Fab")
			(effects
				(font
					(size 1.27 1.27)
				)
			)
		)
		(duplicate_pad_numbers_are_jumpers no)
		(fp_line
			(start -0.7874 -0.4064)
			(end 0.7874 -0.4064)
			(stroke
				(width 0.1524)
				(type default)
			)
			(layer "F.SilkS")
		)
		(fp_line
			(start -0.7874 0.4064)
			(end -0.7874 -0.4064)
			(stroke
				(width 0.1524)
				(type default)
			)
			(layer "F.SilkS")
		)
		(fp_line
			(start 0.7874 -0.4064)
			(end 0.7874 0.4064)
			(stroke
				(width 0.1524)
				(type default)
			)
			(layer "F.SilkS")
		)
		(fp_line
			(start 0.7874 0.4064)
			(end -0.7874 0.4064)
			(stroke
				(width 0.1524)
				(type default)
			)
			(layer "F.SilkS")
		)
		(fp_line
			(start -0.67945 -0.305054)
			(end -0.12065 -0.305054)
			(stroke
				(width 0.1)
				(type default)
			)
			(layer "F.Fab")
		)
		(fp_line
			(start -0.67945 0.3048)
			(end -0.67945 -0.305054)
			(stroke
				(width 0.1)
				(type default)
			)
			(layer "F.Fab")
		)
		(fp_line
			(start -0.12065 -0.305054)
			(end -0.12065 -0.2794)
			(stroke
				(width 0.1)
				(type default)
			)
			(layer "F.Fab")
		)
		(fp_line
			(start -0.12065 -0.2794)
			(end 0.12065 -0.2794)
			(stroke
				(width 0.1)
				(type default)
			)
			(layer "F.Fab")
		)
		(fp_line
			(start -0.12065 0.2794)
			(end -0.12065 0.3048)
			(stroke
				(width 0.1)
				(type default)
			)
			(layer "F.Fab")
		)
		(fp_line
			(start -0.12065 0.3048)
			(end -0.67945 0.3048)
			(stroke
				(width 0.1)
				(type default)
			)
			(layer "F.Fab")
		)
		(fp_line
			(start 0.120396 0.2794)
			(end -0.12065 0.2794)
			(stroke
				(width 0.1)
				(type default)
			)
			(layer "F.Fab")
		)
		(fp_line
			(start 0.120396 0.3048)
			(end 0.120396 0.2794)
			(stroke
				(width 0.1)
				(type default)
			)
			(layer "F.Fab")
		)
		(fp_line
			(start 0.12065 -0.3048)
			(end 0.67945 -0.3048)
			(stroke
				(width 0.1)
				(type default)
			)
			(layer "F.Fab")
		)
		(fp_line
			(start 0.12065 -0.2794)
			(end 0.12065 -0.3048)
			(stroke
				(width 0.1)
				(type default)
			)
			(layer "F.Fab")
		)
		(fp_line
			(start 0.67945 -0.3048)
			(end 0.67945 0.3048)
			(stroke
				(width 0.1)
				(type default)
			)
			(layer "F.Fab")
		)
		(fp_line
			(start 0.67945 0.3048)
			(end 0.120396 0.3048)
			(stroke
				(width 0.1)
				(type default)
			)
			(layer "F.Fab")
		)
		(pad "1" smd circle
			(at -0.40005 0)
			(size 0 0)
			(layers "F.Cu" "F.Mask" "F.Paste")
			(net "P3V3_AUX")
		)
		(pad "2" smd circle
			(at 0.40005 0)
			(size 0 0)
			(layers "F.Cu" "F.Mask" "F.Paste")
			(net "SSD_0_7_ADC_ALERT_N")
		)
	)
	(footprint ""
		(layer "F.Cu")
		(at 143.562578 -22.937216 90)
		(property "Reference" "R1669"
			(at 0 0 90)
			(layer "F.SilkS")
			(hide yes)
			(effects
				(font
					(size 1.27 1.27)
				)
			)
		)
		(property "Value" ""
			(at 0 0 90)
			(layer "F.Fab")
			(effects
				(font
					(size 1.27 1.27)
				)
			)
		)
		(duplicate_pad_numbers_are_jumpers no)
		(fp_line
			(start 0.7874 -0.4064)
			(end 0.7874 0.4064)
			(stroke
				(width 0.1524)
				(type default)
			)
			(layer "F.SilkS")
		)
		(fp_line
			(start -0.7874 -0.4064)
			(end 0.7874 -0.4064)
			(stroke
				(width 0.1524)
				(type default)
			)
			(layer "F.SilkS")
		)
		(fp_line
			(start 0.7874 0.4064)
			(end -0.7874 0.4064)
			(stroke
				(width 0.1524)
				(type default)
			)
			(layer "F.SilkS")
		)
		(fp_line
			(start -0.7874 0.4064)
			(end -0.7874 -0.4064)
			(stroke
				(width 0.1524)
				(type default)
			)
			(layer "F.SilkS")
		)
		(fp_line
			(start -0.12065 -0.305054)
			(end -0.12065 -0.2794)
			(stroke
				(width 0.1)
				(type default)
			)
			(layer "F.Fab")
		)
		(fp_line
			(start -0.67945 -0.305054)
			(end -0.12065 -0.305054)
			(stroke
				(width 0.1)
				(type default)
			)
			(layer "F.Fab")
		)
		(fp_line
			(start 0.67945 -0.3048)
			(end 0.67945 0.3048)
			(stroke
				(width 0.1)
				(type default)
			)
			(layer "F.Fab")
		)
		(fp_line
			(start 0.12065 -0.3048)
			(end 0.67945 -0.3048)
			(stroke
				(width 0.1)
				(type default)
			)
			(layer "F.Fab")
		)
		(fp_line
			(start 0.12065 -0.2794)
			(end 0.12065 -0.3048)
			(stroke
				(width 0.1)
				(type default)
			)
			(layer "F.Fab")
		)
		(fp_line
			(start -0.12065 -0.2794)
			(end 0.12065 -0.2794)
			(stroke
				(width 0.1)
				(type default)
			)
			(layer "F.Fab")
		)
		(fp_line
			(start 0.120396 0.2794)
			(end -0.12065 0.2794)
			(stroke
				(width 0.1)
				(type default)
			)
			(layer "F.Fab")
		)
		(fp_line
			(start -0.12065 0.2794)
			(end -0.12065 0.3048)
			(stroke
				(width 0.1)
				(type default)
			)
			(layer "F.Fab")
		)
		(fp_line
			(start 0.67945 0.3048)
			(end 0.120396 0.3048)
			(stroke
				(width 0.1)
				(type default)
			)
			(layer "F.Fab")
		)
		(fp_line
			(start 0.120396 0.3048)
			(end 0.120396 0.2794)
			(stroke
				(width 0.1)
				(type default)
			)
			(layer "F.Fab")
		)
		(fp_line
			(start -0.12065 0.3048)
			(end -0.67945 0.3048)
			(stroke
				(width 0.1)
				(type default)
			)
			(layer "F.Fab")
		)
		(fp_line
			(start -0.67945 0.3048)
			(end -0.67945 -0.305054)
			(stroke
				(width 0.1)
				(type default)
			)
			(layer "F.Fab")
		)
		(pad "1" smd circle
			(at -0.40005 0 90)
			(size 0 0)
			(layers "F.Cu" "F.Mask" "F.Paste")
			(net "SMB_BIC_I2C9_MUX0_SSD4_R_SDA")
		)
		(pad "2" smd circle
			(at 0.40005 0 90)
			(size 0 0)
			(layers "F.Cu" "F.Mask" "F.Paste")
			(net "SMB_ISO_SSD4_SDA")
		)
	)
	(footprint ""
		(layer "F.Cu")
		(at 400.567906 -56.353456)
		(property "Reference" "C2872"
			(at 0 0 0)
			(layer "F.SilkS")
			(hide yes)
			(effects
				(font
					(size 1.27 1.27)
				)
			)
		)
		(property "Value" ""
			(at 0 0 0)
			(layer "F.Fab")
			(effects
				(font
					(size 1.27 1.27)
				)
			)
		)
		(duplicate_pad_numbers_are_jumpers no)
		(fp_line
			(start -0.7874 -0.4064)
			(end 0.7874 -0.4064)
			(stroke
				(width 0.1524)
				(type default)
			)
			(layer "F.SilkS")
		)
		(fp_line
			(start -0.7874 0.4064)
			(end -0.7874 -0.4064)
			(stroke
				(width 0.1524)
				(type default)
			)
			(layer "F.SilkS")
		)
		(fp_line
			(start 0.7874 -0.4064)
			(end 0.7874 0.4064)
			(stroke
				(width 0.1524)
				(type default)
			)
			(layer "F.SilkS")
		)
		(fp_line
			(start 0.7874 0.4064)
			(end -0.7874 0.4064)
			(stroke
				(width 0.1524)
				(type default)
			)
			(layer "F.SilkS")
		)
		(fp_line
			(start -0.67945 -0.305054)
			(end -0.12065 -0.305054)
			(stroke
				(width 0.1)
				(type default)
			)
			(layer "F.Fab")
		)
		(fp_line
			(start -0.67945 0.3048)
			(end -0.67945 -0.305054)
			(stroke
				(width 0.1)
				(type default)
			)
			(layer "F.Fab")
		)
		(fp_line
			(start -0.12065 -0.305054)
			(end -0.12065 -0.2794)
			(stroke
				(width 0.1)
				(type default)
			)
			(layer "F.Fab")
		)
		(fp_line
			(start -0.12065 -0.2794)
			(end 0.12065 -0.2794)
			(stroke
				(width 0.1)
				(type default)
			)
			(layer "F.Fab")
		)
		(fp_line
			(start -0.12065 0.2794)
			(end -0.12065 0.3048)
			(stroke
				(width 0.1)
				(type default)
			)
			(layer "F.Fab")
		)
		(fp_line
			(start -0.12065 0.3048)
			(end -0.67945 0.3048)
			(stroke
				(width 0.1)
				(type default)
			)
			(layer "F.Fab")
		)
		(fp_line
			(start 0.120396 0.2794)
			(end -0.12065 0.2794)
			(stroke
				(width 0.1)
				(type default)
			)
			(layer "F.Fab")
		)
		(fp_line
			(start 0.120396 0.3048)
			(end 0.120396 0.2794)
			(stroke
				(width 0.1)
				(type default)
			)
			(layer "F.Fab")
		)
		(fp_line
			(start 0.12065 -0.3048)
			(end 0.67945 -0.3048)
			(stroke
				(width 0.1)
				(type default)
			)
			(layer "F.Fab")
		)
		(fp_line
			(start 0.12065 -0.2794)
			(end 0.12065 -0.3048)
			(stroke
				(width 0.1)
				(type default)
			)
			(layer "F.Fab")
		)
		(fp_line
			(start 0.67945 -0.3048)
			(end 0.67945 0.3048)
			(stroke
				(width 0.1)
				(type default)
			)
			(layer "F.Fab")
		)
		(fp_line
			(start 0.67945 0.3048)
			(end 0.120396 0.3048)
			(stroke
				(width 0.1)
				(type default)
			)
			(layer "F.Fab")
		)
		(pad "1" smd circle
			(at -0.40005 0)
			(size 0 0)
			(layers "F.Cu" "F.Mask" "F.Paste")
			(net "SSD13_PWR_EN_R")
		)
		(pad "2" smd circle
			(at 0.40005 0)
			(size 0 0)
			(layers "F.Cu" "F.Mask" "F.Paste")
			(net "GND")
		)
	)
)
